FILE_TYPE = CONNECTIVITY;
{Allegro Design Entry HDL 16.6-p007 (v16-6-112F) 10/10/2012}
"PAGE_NUMBER" = 193;
0"NC";
1"PVCCMCP_CPU1\g";
2"P1V8_MCP_CPU1\g";
3"PVCCIOMCP_CPU1\g";
4"PVCCIO_CPU1\g";
5"PVCCMCP_CPU1\g";
6"PVCCMCP_CPU1\g";
7"P1V8_MCP_CPU1\g";
8"P1V8_MCP_CPU1\g";
9"PVCCIOMCP_CPU1\g";
10"PVCCIOMCP_CPU1\g";
11"PVCCMCP_CPU1\g"VOLTAGE"1.2V";
12"GND\g";
13"P3V3\g";
14"GND\g";
15"GND\g";
16"GND\g";
17"GND\g";
18"GND\g";
19"GND\g";
20"GND\g";
21"GND\g";
22"P12V_STBY\g";
23"P3V3_STBY\g";
24"P5V_STBY\g";
25"GND\g";
26"GND\g";
27"FM_CPU1_VRM_322M_156M_OSC_EN";
28"VR_PVCCIOMCP_CPU1_XADDR1";
29"VR_PVCCMCP_CPU1_XADDR2";
30"VSENSE_PVCCIOMCP_CPU1_SKT_VSEN";
31"VSENSE_PVCCIOMCP_CPU1_SKT_VRTN";
32"SVID_ALERT0_CPU1_R_N";
33"SVID_CLK1_CPU1_R";
34"SVID_DIO1_CPU1_R";
35"FM_PVCCMCP_CPU1_EN";
36"PWRGD_PVCCMCP_CPU1";
37"SVID_ALERT1_CPU1_R_N";
38"SVID_DIO0_CPU1_R";
39"SMB_VR_STBY_LVC3_SDA";
40"SMB_VR_STBY_LVC3_SCL";
41"SVID_CLK0_CPU1_R";
42"FM_PVCCIOMCP_CPU1_EN";
43"PWRGD_PVCCIOMCP_CPU1";
44"FM_P1V8MCP_CPU1_EN";
45"PWRGD_P1V8MCP_CPU1";
46"CLK_322M_156M_CPU1_OSC_VRM_DN";
47"CLK_322M_156M_CPU1_OSC_VRM_DP";
48"VSENSE_P1V8MCP_CPU1_SKT_VSEN";
49"VSENSE_P1V8MCP_CPU1_SKT_VRTN";
50"VSENSE_PVCCMCP_CPU1_SKT_VRTN";
51"VSENSE_PVCCMCP_CPU1_SKT_VSEN";
%"VCC_CORE"
"1","(-3800,4700)","0","mstr_symbols","I107";
;
CDS_LIB"mstr_symbols"
HDL_POWER"PVCCMCP_CPU1";
"A"1;
%"VCC_CORE"
"1","(-4050,4650)","0","mstr_symbols","I131";
;
CDS_LIB"mstr_symbols"
VOLTAGE"1.8"
HDL_POWER"P1V8_MCP_CPU1";
"A"2;
%"VCC_CORE"
"1","(-5250,3225)","0","mstr_symbols","I134";
;
CDS_LIB"mstr_symbols"
VOLTAGE"+0.95"
HDL_POWER"PVCCIOMCP_CPU1";
"A"3;
%"CAP_A"
"1","(-1950,1875)","0","dev_discrete","I140";
;
SEC"1"
SEC_TYPE"0603V"
CDS_SEC"1"
CDS_LIB"dev_discrete"
CDS_LOCATION"C3F1"
MATERIAL"X5R"
VOLTAGE"4V"
PACK_TYPE"0603V"
TOLERANCE"20%"
VALUE"47UF"
PART_NUMBER"602433-106"
LOCATION"C3F1";
"B"
$PN"2"18;
"A"
$PN"1"7;
%"CAP_A"
"1","(-1700,1875)","0","dev_discrete","I141";
;
SEC"1"
SEC_TYPE"0603V"
CDS_SEC"1"
CDS_LIB"dev_discrete"
CDS_LOCATION"C4F2"
MATERIAL"X5R"
VOLTAGE"4V"
PACK_TYPE"0603V"
TOLERANCE"20%"
VALUE"47UF"
PART_NUMBER"602433-106"
LOCATION"C4F2";
"B"
$PN"2"18;
"A"
$PN"1"7;
%"PVCCIO_CPU1"
"1","(-7225,4575)","0","mstr_symbols","I144";
;
HDL_POWER"PVCCIO_CPU1"
ROOM"PVCCIO_CPU1"
BODY_TYPE"PLUMBING"
BOM_COST"PROC_VRD_PVCCIO_CPU1"
CDS_LIB"mstr_symbols"
VOLTAGE"1.1V";
"G\NAC"4;
%"VCC_CORE"
"1","(-2300,4600)","0","mstr_symbols","I161";
;
CDS_LIB"mstr_symbols"
VOLTAGE"+0.95"
HDL_POWER"PVCCMCP_CPU1";
"A"5;
%"VCC_CORE"
"1","(-5075,3700)","0","mstr_symbols","I162";
;
CDS_LIB"mstr_symbols"
HDL_POWER"PVCCMCP_CPU1";
"A"6;
%"VCC_CORE"
"1","(-1700,2125)","0","mstr_symbols","I164";
;
CDS_LIB"mstr_symbols"
VOLTAGE"1.8"
HDL_POWER"P1V8_MCP_CPU1";
"A"7;
%"VCC_CORE"
"1","(-1225,2250)","0","mstr_symbols","I165";
;
CDS_LIB"mstr_symbols"
VOLTAGE"1.8"
HDL_POWER"P1V8_MCP_CPU1";
"A"8;
%"VCC_CORE"
"1","(-1150,4600)","0","mstr_symbols","I166";
;
CDS_LIB"mstr_symbols"
VOLTAGE"+0.95"
HDL_POWER"PVCCIOMCP_CPU1";
"A"9;
%"VCC_CORE"
"1","(-1775,4600)","0","mstr_symbols","I167";
;
CDS_LIB"mstr_symbols"
VOLTAGE"+0.95"
HDL_POWER"PVCCIOMCP_CPU1";
"A"10;
%"VCC_CORE"
"1","(-1550,3275)","0","mstr_symbols","I168";
;
CDS_LIB"mstr_symbols"
VOLTAGE"+0.95"
HDL_POWER"PVCCMCP_CPU1";
"A"11;
%"RES"
"2","(-7950,775)","0","mstr_discrete","I169";
;
CDS_SEC"1"
CDS_LOCATION"R4C12"
ROOM"PVCCIN_CPU0_VR"
SEC"1"
CDS_LIB"mstr_discrete"
SEC_TYPE"0402"
WATTAGE"1/16W"
MATERIAL"CHIP"
PACK_TYPE"0402"
TOLERANCE"1%"
VALUE"8.06K"
PART_NUMBER"G21796-078"
LOCATION"R4C12";
"A"
$PN"1"28;
"B"
$PN"2"12;
%"RES"
"2","(-7600,750)","0","mstr_discrete","I170";
;
CDS_SEC"1"
CDS_LOCATION"R4C11"
ROOM"PVCCIN_CPU0_VR"
SEC"1"
CDS_LIB"mstr_discrete"
SEC_TYPE"0402"
WATTAGE"1/16W"
MATERIAL"CHIP"
PACK_TYPE"0402"
TOLERANCE"1%"
VALUE"3.16K"
PART_NUMBER"G21796-043"
LOCATION"R4C11";
"A"
$PN"1"29;
"B"
$PN"2"12;
%"GND"
"1","(-7750,425)","0","mstr_symbols","I171";
;
HDL_POWER"GND"
BODY_TYPE"PLUMBING"
SIZE"1B"
CDS_LIB"mstr_symbols"
VOLTAGE"0.0V";
"A\NAC"12;
%"P3V3"
"1","(-7325,4500)","0","mstr_symbols","I173";
;
HDL_POWER"P3V3"
BODY_TYPE"PLUMBING"
CDS_LIB"mstr_symbols"
SIZE"1B"
VOLTAGE"+3.3V";
"G\NAC"13;
%"CAPP"
"1","(-1775,4275)","0","mstr_discrete","I29";
;
CDS_SEC"1"
ROOM"P0V95_MCP_CPU1_DECAP_VR"
CDS_LOCATION"C4C1"
SEC"1"
BOM_COST"PROC_VRD_VCCIN_CPU1"
SEC_TYPE"3018"
CDS_LIB"mstr_discrete"
MATERIAL"ALUM"
VOLTAGE"2.5V"
PACK_TYPE"3018"
TOLERANCE"20%"
VALUE"470UF"
PART_NUMBER"699013-049"
LOCATION"C4C1";
"B"
$PN"2"14;
"A"
$PN"1"10;
%"GND"
"1","(-1775,3875)","0","mstr_symbols","I30";
;
HDL_POWER"GND"
ROOM"PVSA_CPU0_DECAP_VR"
BODY_TYPE"PLUMBING"
BOM_COST"PROC_VRD_VCCIN_CPU0"
CDS_LIB"mstr_symbols"
SIZE"1B"
VOLTAGE"0";
"A\NAC"14;
%"CAP_A"
"1","(-700,4225)","2","dev_discrete","I31";
;
ROOM"P0V95_FPGA_CPU1"
SEC"1"
SEC_TYPE"0402V"
CDS_SEC"1"
CDS_LIB"dev_discrete"
CDS_LOCATION"C3C2"
MATERIAL"X6S"
VOLTAGE"6.3V"
PACK_TYPE"0402V"
TOLERANCE"10%"
VALUE"1.0UF"
PART_NUMBER"D97712-004"
LOCATION"C3C2";
"B"
$PN"2"15;
"A"
$PN"1"9;
%"GND"
"1","(-1150,3850)","0","mstr_symbols","I37";
;
HDL_POWER"GND"
BODY_TYPE"PLUMBING"
SIZE"1B"
CDS_LIB"mstr_symbols"
VOLTAGE"0.0V";
"A\NAC"15;
%"CAP_A"
"1","(-1150,4200)","2","dev_discrete","I38";
;
ROOM"P0V95_FPGA_CPU1"
SEC"1"
SEC_TYPE"0402V"
CDS_SEC"1"
CDS_LIB"dev_discrete"
CDS_LOCATION"C3C1"
MATERIAL"X6S"
VOLTAGE"6.3V"
PACK_TYPE"0402V"
TOLERANCE"10%"
VALUE"1.0UF"
PART_NUMBER"D97712-004"
LOCATION"C3C1";
"B"
$PN"2"15;
"A"
$PN"1"9;
%"SCONN120_H61426002"
"1","(-3150,2800)","0","mstr_sconn","I45";
;
CDS_SEC"1"
ROOM"MCP VRM CPU1"
CDS_LOCATION"J4E1"
SEC"1"
SEC_TYPE"SM"
CDS_LIB"mstr_sconn"
PACK_TYPE"SM"
MATERIAL"CONN"
PART_NUMBER"H61426-002"
LOCATION"J4E1";
"IOB11"
$PN"B11"5;
"IOA1"
$PN"A1"1;
"IOB1"
$PN"B1"1;
"IOD1"
$PN"D1"48;
"IOC1"
$PN"C1"1;
"IOE1"
$PN"E1"2;
"IOF1"
$PN"F1"2;
"IOB2"
$PN"B2"1;
"IOA2"
$PN"A2"1;
"IOC2"
$PN"C2"1;
"IOD2"
$PN"D2"49;
"IOE2"
$PN"E2"2;
"IOF2"
$PN"F2"2;
"IOB3"
$PN"B3"1;
"IOA3"
$PN"A3"1;
"IOC3"
$PN"C3"1;
"IOD3"
$PN"D3"17;
"IOE3"
$PN"E3"17;
"IOF3"
$PN"F3"17;
"IOA4"
$PN"A4"51;
"IOB4"
$PN"B4"50;
"IOC4"
$PN"C4"6;
"IOD4"
$PN"D4"17;
"IOF4"
$PN"F4"17;
"IOE4"
$PN"E4"17;
"IOA5"
$PN"A5"6;
"IOB5"
$PN"B5"6;
"IOD5"
$PN"D5"17;
"IOC5"
$PN"C5"6;
"IOF5"
$PN"F5"46;
"IOE5"
$PN"E5"47;
"IOA6"
$PN"A6"6;
"IOB6"
$PN"B6"6;
"IOD6"
$PN"D6"17;
"IOC6"
$PN"C6"6;
"IOE6"
$PN"E6"17;
"IOF6"
$PN"F6"17;
"IOA7"
$PN"A7"6;
"IOC7"
$PN"C7"6;
"IOB7"
$PN"B7"6;
"IOE7"
$PN"E7"17;
"IOD7"
$PN"D7"17;
"IOF7"
$PN"F7"17;
"IOA8"
$PN"A8"6;
"IOB8"
$PN"B8"6;
"IOC8"
$PN"C8"6;
"IOD8"
$PN"D8"17;
"IOF8"
$PN"F8"17;
"IOE8"
$PN"E8"17;
"IOB9"
$PN"B9"6;
"IOA9"
$PN"A9"6;
"IOC9"
$PN"C9"6;
"IOD9"
$PN"D9"17;
"IOE9"
$PN"E9"17;
"IOF9"
$PN"F9"17;
"IOA10"
$PN"A10"6;
"IOB10"
$PN"B10"6;
"IOC10"
$PN"C10"6;
"IOE10"
$PN"E10"17;
"IOD10"
$PN"D10"17;
"IOF10"
$PN"F10"17;
"IOA11"
$PN"A11"5;
"IOC11"
$PN"C11"5;
"IOD11"
$PN"D11"16;
"IOE11"
$PN"E11"16;
"IOF11"
$PN"F11"16;
"IOA12"
$PN"A12"5;
"IOB12"
$PN"B12"5;
"IOD12"
$PN"D12"16;
"IOC12"
$PN"C12"5;
"IOF12"
$PN"F12"16;
"IOE12"
$PN"E12"16;
"IOA13"
$PN"A13"5;
"IOB13"
$PN"B13"5;
"IOC13"
$PN"C13"5;
"IOE13"
$PN"E13"16;
"IOD13"
$PN"D13"16;
"IOF13"
$PN"F13"16;
"IOA14"
$PN"A14"5;
"IOC14"
$PN"C14"5;
"IOB14"
$PN"B14"5;
"IOE14"
$PN"E14"16;
"IOD14"
$PN"D14"16;
"IOF14"
$PN"F14"16;
"IOA15"
$PN"A15"5;
"IOB15"
$PN"B15"5;
"IOC15"
$PN"C15"5;
"IOD15"
$PN"D15"16;
"IOF15"
$PN"F15"16;
"IOE15"
$PN"E15"16;
"IOA16"
$PN"A16"5;
"IOB16"
$PN"B16"5;
"IOC16"
$PN"C16"5;
"IOD16"
$PN"D16"16;
"IOE16"
$PN"E16"16;
"IOF16"
$PN"F16"16;
"IOA17"
$PN"A17"5;
"IOB17"
$PN"B17"5;
"IOC17"
$PN"C17"5;
"IOD17"
$PN"D17"16;
"IOE17"
$PN"E17"16;
"IOF17"
$PN"F17"16;
"IOA18"
$PN"A18"5;
"IOC18"
$PN"C18"5;
"IOB18"
$PN"B18"5;
"IOD18"
$PN"D18"16;
"IOE18"
$PN"E18"16;
"IOF18"
$PN"F18"16;
"IOA19"
$PN"A19"16;
"IOB19"
$PN"B19"16;
"IOD19"
$PN"D19"16;
"IOC19"
$PN"C19"16;
"IOF19"
$PN"F19"16;
"IOE19"
$PN"E19"16;
"IOB20"
$PN"B20"16;
"IOA20"
$PN"A20"16;
"IOD20"
$PN"D20"16;
"IOC20"
$PN"C20"16;
"IOE20"
$PN"E20"16;
"IOF20"
$PN"F20"16;
%"SCONN120_H61426002"
"1","(-6325,2725)","0","mstr_sconn","I46";
;
CDS_SEC"1"
ROOM"MCP VRM CPU1"
CDS_LOCATION"J4B2"
SEC"1"
SEC_TYPE"SM"
CDS_LIB"mstr_sconn"
PACK_TYPE"SM"
MATERIAL"CONN"
PART_NUMBER"H61426-002"
LOCATION"J4B2";
"IOB11"
$PN"B11"23;
"IOA1"
$PN"A1"22;
"IOB1"
$PN"B1"22;
"IOD1"
$PN"D1"13;
"IOC1"
$PN"C1"21;
"IOE1"
$PN"E1"27;
"IOF1"
$PN"F1"4;
"IOB2"
$PN"B2"22;
"IOA2"
$PN"A2"22;
"IOC2"
$PN"C2"21;
"IOD2"
$PN"D2"21;
"IOE2"
$PN"E2"21;
"IOF2"
$PN"F2"21;
"IOB3"
$PN"B3"22;
"IOA3"
$PN"A3"22;
"IOC3"
$PN"C3"21;
"IOD3"
$PN"D3"21;
"IOE3"
$PN"E3"21;
"IOF3"
$PN"F3"21;
"IOA4"
$PN"A4"22;
"IOB4"
$PN"B4"22;
"IOC4"
$PN"C4"21;
"IOD4"
$PN"D4"21;
"IOF4"
$PN"F4"21;
"IOE4"
$PN"E4"21;
"IOA5"
$PN"A5"22;
"IOB5"
$PN"B5"22;
"IOD5"
$PN"D5"21;
"IOC5"
$PN"C5"21;
"IOF5"
$PN"F5"21;
"IOE5"
$PN"E5"21;
"IOA6"
$PN"A6"22;
"IOB6"
$PN"B6"22;
"IOD6"
$PN"D6"21;
"IOC6"
$PN"C6"21;
"IOE6"
$PN"E6"21;
"IOF6"
$PN"F6"21;
"IOA7"
$PN"A7"22;
"IOC7"
$PN"C7"21;
"IOB7"
$PN"B7"22;
"IOE7"
$PN"E7"21;
"IOD7"
$PN"D7"21;
"IOF7"
$PN"F7"21;
"IOA8"
$PN"A8"22;
"IOB8"
$PN"B8"22;
"IOC8"
$PN"C8"26;
"IOD8"
$PN"D8"26;
"IOF8"
$PN"F8"31;
"IOE8"
$PN"E8"30;
"IOB9"
$PN"B9"26;
"IOA9"
$PN"A9"26;
"IOC9"
$PN"C9"26;
"IOD9"
$PN"D9"26;
"IOE9"
$PN"E9"26;
"IOF9"
$PN"F9"26;
"IOA10"
$PN"A10"26;
"IOB10"
$PN"B10"26;
"IOC10"
$PN"C10"26;
"IOE10"
$PN"E10"28;
"IOD10"
$PN"D10"26;
"IOF10"
$PN"F10"29;
"IOA11"
$PN"A11"23;
"IOC11"
$PN"C11"23;
"IOD11"
$PN"D11"25;
"IOE11"
$PN"E11"25;
"IOF11"
$PN"F11"25;
"IOA12"
$PN"A12"25;
"IOB12"
$PN"B12"25;
"IOD12"
$PN"D12"25;
"IOC12"
$PN"C12"25;
"IOF12"
$PN"F12"25;
"IOE12"
$PN"E12"25;
"IOA13"
$PN"A13"24;
"IOB13"
$PN"B13"24;
"IOC13"
$PN"C13"24;
"IOE13"
$PN"E13"25;
"IOD13"
$PN"D13"25;
"IOF13"
$PN"F13"25;
"IOA14"
$PN"A14"25;
"IOC14"
$PN"C14"25;
"IOB14"
$PN"B14"25;
"IOE14"
$PN"E14"25;
"IOD14"
$PN"D14"25;
"IOF14"
$PN"F14"25;
"IOA15"
$PN"A15"44;
"IOB15"
$PN"B15"45;
"IOC15"
$PN"C15"25;
"IOD15"
$PN"D15"3;
"IOF15"
$PN"F15"3;
"IOE15"
$PN"E15"3;
"IOA16"
$PN"A16"42;
"IOB16"
$PN"B16"43;
"IOC16"
$PN"C16"25;
"IOD16"
$PN"D16"3;
"IOE16"
$PN"E16"3;
"IOF16"
$PN"F16"3;
"IOA17"
$PN"A17"25;
"IOB17"
$PN"B17"25;
"IOC17"
$PN"C17"3;
"IOD17"
$PN"D17"3;
"IOE17"
$PN"E17"3;
"IOF17"
$PN"F17"3;
"IOA18"
$PN"A18"40;
"IOC18"
$PN"C18"3;
"IOB18"
$PN"B18"39;
"IOD18"
$PN"D18"3;
"IOE18"
$PN"E18"3;
"IOF18"
$PN"F18"3;
"IOA19"
$PN"A19"32;
"IOB19"
$PN"B19"37;
"IOD19"
$PN"D19"3;
"IOC19"
$PN"C19"3;
"IOF19"
$PN"F19"3;
"IOE19"
$PN"E19"3;
"IOB20"
$PN"B20"38;
"IOA20"
$PN"A20"41;
"IOD20"
$PN"D20"36;
"IOC20"
$PN"C20"35;
"IOE20"
$PN"E20"33;
"IOF20"
$PN"F20"34;
%"GND"
"1","(-2150,950)","0","mstr_symbols","I56";
;
HDL_POWER"GND"
BODY_TYPE"PLUMBING"
SIZE"1B"
CDS_LIB"mstr_symbols"
VOLTAGE"0.0V";
"A\NAC"16;
%"GND"
"1","(-3975,925)","0","mstr_symbols","I60";
;
HDL_POWER"GND"
BODY_TYPE"PLUMBING"
CDS_LIB"mstr_symbols"
SIZE"1B"
VOLTAGE"0.0V";
"A\NAC"17;
%"CAPP"
"1","(-1675,2975)","0","mstr_discrete","I61";
;
ROOM"PVMCP_MCP_CPU1_VR"
CDS_LOCATION"C4E24"
$SEC"1"
CDS_SEC"1"
BOM_COST"PVMCP_MCP_CPU1_VR"
CDS_LIB"mstr_discrete"
VOLTAGE"2.5V"
MATERIAL"ALUM"
PACK_TYPE"3018"
TOLERANCE"20%"
VALUE"470UF"
PART_NUMBER"699013-049"
LOCATION"C4E24";
"B"
$PN"2"20;
"A"
$PN"1"11;
%"CAPP"
"1","(-1400,2975)","0","mstr_discrete","I62";
;
CDS_SEC"1"
ROOM"PVMCP_MCP_CPU1_VR"
CDS_LOCATION"C6R16"
SEC"1"
CDS_LIB"mstr_discrete"
BOM_COST"PVMCP_MCP_CPU1_VR"
SEC_TYPE"3018"
VOLTAGE"2.5V"
MATERIAL"ALUM"
PACK_TYPE"3018"
TOLERANCE"20%"
VALUE"470UF"
PART_NUMBER"699013-049"
LOCATION"C6R16";
"B"
$PN"2"20;
"A"
$PN"1"11;
%"GND"
"1","(-1700,1525)","0","mstr_symbols","I64";
;
HDL_POWER"GND"
BODY_TYPE"PLUMBING"
SIZE"1B"
CDS_LIB"mstr_symbols"
VOLTAGE"0";
"A\NAC"18;
%"CAP_A"
"1","(-775,1850)","2","dev_discrete","I68";
;
ROOM"P1V8_MCP_CPU1"
SEC"1"
SEC_TYPE"0402V"
CDS_SEC"1"
CDS_LIB"dev_discrete"
CDS_LOCATION"C4F1"
MATERIAL"X6S"
VOLTAGE"6.3V"
PACK_TYPE"0402V"
TOLERANCE"10%"
VALUE"1.0UF"
PART_NUMBER"D97712-004"
LOCATION"C4F1";
"B"
$PN"2"19;
"A"
$PN"1"8;
%"CAP_A"
"1","(-1225,1850)","2","dev_discrete","I70";
;
ROOM"P1V8_MCP_CPU1"
SEC"1"
SEC_TYPE"0402V"
CDS_SEC"1"
CDS_LIB"dev_discrete"
CDS_LOCATION"C4F3"
MATERIAL"X6S"
VOLTAGE"6.3V"
PACK_TYPE"0402V"
TOLERANCE"10%"
VALUE"1.0UF"
PART_NUMBER"D97712-004"
LOCATION"C4F3";
"B"
$PN"2"19;
"A"
$PN"1"8;
%"GND"
"1","(-1225,1500)","0","mstr_symbols","I75";
;
HDL_POWER"GND"
BODY_TYPE"PLUMBING"
CDS_LIB"mstr_symbols"
SIZE"1B"
VOLTAGE"0.0V";
"A\NAC"19;
%"GND"
"1","(-1525,2675)","0","mstr_symbols","I81";
;
HDL_POWER"GND"
ROOM"PVSA_CPU0_DECAP_VR"
BODY_TYPE"PLUMBING"
CDS_LIB"mstr_symbols"
SIZE"1B"
BOM_COST"PROC_VRD_VCCIN_CPU0"
VOLTAGE"0";
"A\NAC"20;
%"GND"
"1","(-7150,1875)","0","mstr_symbols","I85";
;
HDL_POWER"GND"
BODY_TYPE"PLUMBING"
SIZE"1B"
CDS_LIB"mstr_symbols"
VOLTAGE"0.0V";
"A\NAC"21;
%"P12V_STBY"
"1","(-6950,4750)","0","mstr_symbols","I86";
;
HDL_POWER"P12V_STBY"
BODY_TYPE"PLUMBING"
SIZE"1B"
CDS_LIB"mstr_symbols"
VOLTAGE"12.0V";
"G\NAC"22;
%"P3V3_STBY"
"1","(-5525,4525)","0","mstr_symbols","I87";
;
HDL_POWER"P3V3_STBY"
BODY_TYPE"PLUMBING"
SIZE"1B"
CDS_LIB"mstr_symbols"
VOLTAGE"+3.3V";
"G\NAC"23;
%"P5V_STBY"
"1","(-5500,3850)","0","mstr_symbols","I88";
;
HDL_POWER"P5V_STBY"
BODY_TYPE"PLUMBING"
SIZE"1B"
CDS_LIB"mstr_symbols"
VOLTAGE"+5.0V";
"G\NAC"24;
%"GND"
"1","(-5125,2175)","0","mstr_symbols","I94";
;
HDL_POWER"GND"
BODY_TYPE"PLUMBING"
SIZE"1B"
CDS_LIB"mstr_symbols"
VOLTAGE"0.0V";
"A\NAC"25;
%"GND"
"1","(-7125,1425)","0","mstr_symbols","I95";
;
HDL_POWER"GND"
BODY_TYPE"PLUMBING"
SIZE"1B"
CDS_LIB"mstr_symbols"
VOLTAGE"0.0V";
"A\NAC"26;
END.
